# T6G (Grand Teton) — schematic netlist excerpt (pin names and nets, part order shuffled) for the footprints in the layout excerpt that follows; sources: Cadence DE-HDL packaged netlist, KiCad conversion of 04192023_DAF0TMB3IC0_F0TG_MB_C_brd_V02_OCP.brd

C62  Q_CAP  220PF 50V 5% C0G  pkg C0402  page 151 : A = UART_CPU0_SCM_LVC3_UART1_TX ; B = GND
R1908  Q_RES  1K 1% CHIP  pkg 0402LF  page 134 : A = P3V3_AUX ; B = OCP_SFF_PRSNT3_R_N
C6707  Q_CAP_DIFFBUS  DIFF BUS_0.22UF 6.3V 20% X6S  pkg C0201  page 341 : \1\ = P5E_CPU1_P2_TX_BUF_C_DP<7> ; \2\ = P5E_CPU1_P2_TX_BUF_DP<7>

(kicad_pcb
	(version 20260206)
	(generator "pcbnew")
	(generator_version "10.0")
	(general
		(thickness 1.6)
		(legacy_teardrops no)
	)
	(paper "A4")
	(title_block
		(title "04192023_DAF0TMB3IC0_F0TG_MB_C_brd_V02_OCP.brd")
		(comment 1 "Grand Teton / footprints 3284-3286 of 8354")
	)
	(layers
		(0 "F.Cu" signal "TOP")
		(4 "In1.Cu" signal "GND")
		(6 "In2.Cu" signal "IN1")
		(8 "In3.Cu" signal "GND1")
		(10 "In4.Cu" signal "IN2")
		(12 "In5.Cu" signal "GND2")
		(14 "In6.Cu" signal "IN3")
		(16 "In7.Cu" signal "GND3")
		(18 "In8.Cu" signal "VCC")
		(20 "In9.Cu" signal "VCC1")
		(22 "In10.Cu" signal "GND4")
		(24 "In11.Cu" signal "IN4")
		(26 "In12.Cu" signal "GND5")
		(28 "In13.Cu" signal "IN5")
		(30 "In14.Cu" signal "GND6")
		(32 "In15.Cu" signal "IN6")
		(34 "In16.Cu" signal "GND7")
		(2 "B.Cu" signal "BOTTOM")
		(9 "F.Adhes" user "F.Adhesive")
		(11 "B.Adhes" user "B.Adhesive")
		(13 "F.Paste" user "Package Geometry/Pastemask Top")
		(15 "B.Paste" user "Package Geometry/Pastemask Bottom")
		(5 "F.SilkS" user "Ref Des/Silkscreen Top")
		(7 "B.SilkS" user "Ref Des/Silkscreen Bottom")
		(1 "F.Mask" user "Board Geometry/Soldermask Top")
		(3 "B.Mask" user "Board Geometry/Soldermask Bottom")
		(17 "Dwgs.User" user "User.Drawings")
		(19 "Cmts.User" user "User.Comments")
		(21 "Eco1.User" user "User.Eco1")
		(23 "Eco2.User" user "User.Eco2")
		(25 "Edge.Cuts" user "Board Geometry/Outline")
		(27 "Margin" user)
		(31 "F.CrtYd" user "Package Geometry/Place Bound Top")
		(29 "B.CrtYd" user "Package Geometry/Place Bound Bottom")
		(35 "F.Fab" user "Ref Des/Assembly Top")
		(33 "B.Fab" user "Ref Des/Assembly Bottom")
	)
	(footprint ""
		(layer "F.Cu")
		(at 308.757574 -22.185884 90)
		(property "Reference" "C62"
			(at 0 0 90)
			(layer "F.SilkS")
			(hide yes)
			(effects
				(font
					(size 1.27 1.27)
				)
			)
		)
		(property "Value" ""
			(at 0 0 90)
			(layer "F.Fab")
			(effects
				(font
					(size 1.27 1.27)
				)
			)
		)
		(duplicate_pad_numbers_are_jumpers no)
		(fp_line
			(start 0.7874 -0.4064)
			(end 0.7874 0.4064)
			(stroke
				(width 0.1524)
				(type default)
			)
			(layer "F.SilkS")
		)
		(fp_line
			(start -0.7874 -0.4064)
			(end 0.7874 -0.4064)
			(stroke
				(width 0.1524)
				(type default)
			)
			(layer "F.SilkS")
		)
		(fp_line
			(start 0.7874 0.4064)
			(end -0.7874 0.4064)
			(stroke
				(width 0.1524)
				(type default)
			)
			(layer "F.SilkS")
		)
		(fp_line
			(start -0.7874 0.4064)
			(end -0.7874 -0.4064)
			(stroke
				(width 0.1524)
				(type default)
			)
			(layer "F.SilkS")
		)
		(fp_line
			(start -0.12065 -0.305054)
			(end -0.12065 -0.2794)
			(stroke
				(width 0.1)
				(type default)
			)
			(layer "F.Fab")
		)
		(fp_line
			(start -0.67945 -0.305054)
			(end -0.12065 -0.305054)
			(stroke
				(width 0.1)
				(type default)
			)
			(layer "F.Fab")
		)
		(fp_line
			(start 0.67945 -0.3048)
			(end 0.67945 0.3048)
			(stroke
				(width 0.1)
				(type default)
			)
			(layer "F.Fab")
		)
		(fp_line
			(start 0.12065 -0.3048)
			(end 0.67945 -0.3048)
			(stroke
				(width 0.1)
				(type default)
			)
			(layer "F.Fab")
		)
		(fp_line
			(start 0.12065 -0.2794)
			(end 0.12065 -0.3048)
			(stroke
				(width 0.1)
				(type default)
			)
			(layer "F.Fab")
		)
		(fp_line
			(start -0.12065 -0.2794)
			(end 0.12065 -0.2794)
			(stroke
				(width 0.1)
				(type default)
			)
			(layer "F.Fab")
		)
		(fp_line
			(start 0.120396 0.2794)
			(end -0.12065 0.2794)
			(stroke
				(width 0.1)
				(type default)
			)
			(layer "F.Fab")
		)
		(fp_line
			(start -0.12065 0.2794)
			(end -0.12065 0.3048)
			(stroke
				(width 0.1)
				(type default)
			)
			(layer "F.Fab")
		)
		(fp_line
			(start 0.67945 0.3048)
			(end 0.120396 0.3048)
			(stroke
				(width 0.1)
				(type default)
			)
			(layer "F.Fab")
		)
		(fp_line
			(start 0.120396 0.3048)
			(end 0.120396 0.2794)
			(stroke
				(width 0.1)
				(type default)
			)
			(layer "F.Fab")
		)
		(fp_line
			(start -0.12065 0.3048)
			(end -0.67945 0.3048)
			(stroke
				(width 0.1)
				(type default)
			)
			(layer "F.Fab")
		)
		(fp_line
			(start -0.67945 0.3048)
			(end -0.67945 -0.305054)
			(stroke
				(width 0.1)
				(type default)
			)
			(layer "F.Fab")
		)
		(pad "1" smd circle
			(at -0.40005 0 90)
			(size 0 0)
			(layers "F.Cu" "F.Mask" "F.Paste")
			(net "UART_CPU0_SCM_LVC3_UART1_TX")
		)
		(pad "2" smd circle
			(at 0.40005 0 90)
			(size 0 0)
			(layers "F.Cu" "F.Mask" "F.Paste")
			(net "GND")
		)
	)
	(footprint ""
		(layer "F.Cu")
		(at 137.225786 -408.517344 -90)
		(property "Reference" "C6707"
			(at 0 0 270)
			(layer "F.SilkS")
			(hide yes)
			(effects
				(font
					(size 1.27 1.27)
				)
			)
		)
		(property "Value" ""
			(at 0 0 270)
			(layer "F.Fab")
			(effects
				(font
					(size 1.27 1.27)
				)
			)
		)
		(duplicate_pad_numbers_are_jumpers no)
		(fp_line
			(start -0.299974 0.150114)
			(end -0.299974 -0.150114)
			(stroke
				(width 0.1)
				(type default)
			)
			(layer "F.Fab")
		)
		(fp_line
			(start 0.299974 0.150114)
			(end -0.299974 0.150114)
			(stroke
				(width 0.1)
				(type default)
			)
			(layer "F.Fab")
		)
		(fp_line
			(start -0.299974 -0.150114)
			(end 0.299974 -0.150114)
			(stroke
				(width 0.1)
				(type default)
			)
			(layer "F.Fab")
		)
		(fp_line
			(start 0.299974 -0.150114)
			(end 0.299974 0.150114)
			(stroke
				(width 0.1)
				(type default)
			)
			(layer "F.Fab")
		)
		(pad "1" smd rect
			(at -0.2667 0 270)
			(size 0.3048 0.381)
			(layers "F.Cu" "F.Mask" "F.Paste")
			(net "P5E_CPU1_P2_TX_BUF_C_DP<7>")
		)
		(pad "2" smd rect
			(at 0.2667 0 270)
			(size 0.3048 0.381)
			(layers "F.Cu" "F.Mask" "F.Paste")
			(net "P5E_CPU1_P2_TX_BUF_DP<7>")
		)
	)
	(footprint ""
		(layer "F.Cu")
		(at 453.719946 -102.598728)
		(property "Reference" "R1908"
			(at 0 0 0)
			(layer "F.SilkS")
			(hide yes)
			(effects
				(font
					(size 1.27 1.27)
				)
			)
		)
		(property "Value" ""
			(at 0 0 0)
			(layer "F.Fab")
			(effects
				(font
					(size 1.27 1.27)
				)
			)
		)
		(duplicate_pad_numbers_are_jumpers no)
		(fp_line
			(start -0.7874 -0.4064)
			(end 0.7874 -0.4064)
			(stroke
				(width 0.1524)
				(type default)
			)
			(layer "F.SilkS")
		)
		(fp_line
			(start -0.7874 0.4064)
			(end -0.7874 -0.4064)
			(stroke
				(width 0.1524)
				(type default)
			)
			(layer "F.SilkS")
		)
		(fp_line
			(start 0.7874 -0.4064)
			(end 0.7874 0.4064)
			(stroke
				(width 0.1524)
				(type default)
			)
			(layer "F.SilkS")
		)
		(fp_line
			(start 0.7874 0.4064)
			(end -0.7874 0.4064)
			(stroke
				(width 0.1524)
				(type default)
			)
			(layer "F.SilkS")
		)
		(fp_line
			(start -0.67945 -0.305054)
			(end -0.12065 -0.305054)
			(stroke
				(width 0.1)
				(type default)
			)
			(layer "F.Fab")
		)
		(fp_line
			(start -0.67945 0.3048)
			(end -0.67945 -0.305054)
			(stroke
				(width 0.1)
				(type default)
			)
			(layer "F.Fab")
		)
		(fp_line
			(start -0.12065 -0.305054)
			(end -0.12065 -0.2794)
			(stroke
				(width 0.1)
				(type default)
			)
			(layer "F.Fab")
		)
		(fp_line
			(start -0.12065 -0.2794)
			(end 0.12065 -0.2794)
			(stroke
				(width 0.1)
				(type default)
			)
			(layer "F.Fab")
		)
		(fp_line
			(start -0.12065 0.2794)
			(end -0.12065 0.3048)
			(stroke
				(width 0.1)
				(type default)
			)
			(layer "F.Fab")
		)
		(fp_line
			(start -0.12065 0.3048)
			(end -0.67945 0.3048)
			(stroke
				(width 0.1)
				(type default)
			)
			(layer "F.Fab")
		)
		(fp_line
			(start 0.120396 0.2794)
			(end -0.12065 0.2794)
			(stroke
				(width 0.1)
				(type default)
			)
			(layer "F.Fab")
		)
		(fp_line
			(start 0.120396 0.3048)
			(end 0.120396 0.2794)
			(stroke
				(width 0.1)
				(type default)
			)
			(layer "F.Fab")
		)
		(fp_line
			(start 0.12065 -0.3048)
			(end 0.67945 -0.3048)
			(stroke
				(width 0.1)
				(type default)
			)
			(layer "F.Fab")
		)
		(fp_line
			(start 0.12065 -0.2794)
			(end 0.12065 -0.3048)
			(stroke
				(width 0.1)
				(type default)
			)
			(layer "F.Fab")
		)
		(fp_line
			(start 0.67945 -0.3048)
			(end 0.67945 0.3048)
			(stroke
				(width 0.1)
				(type default)
			)
			(layer "F.Fab")
		)
		(fp_line
			(start 0.67945 0.3048)
			(end 0.120396 0.3048)
			(stroke
				(width 0.1)
				(type default)
			)
			(layer "F.Fab")
		)
		(pad "1" smd circle
			(at -0.40005 0)
			(size 0 0)
			(layers "F.Cu" "F.Mask" "F.Paste")
			(net "P3V3_AUX")
		)
		(pad "2" smd circle
			(at 0.40005 0)
			(size 0 0)
			(layers "F.Cu" "F.Mask" "F.Paste")
			(net "OCP_SFF_PRSNT3_R_N")
		)
	)
)
